(kicad_pcb
	(version 20241229)
	(generator "pcbnew")
	(generator_version "9.0")
	(general
		(thickness 1.294)
		(legacy_teardrops no)
	)
	(paper "A3")
	(title_block
		(title "Kintex 410T devboard")
		(date "2024-04-03")
		(rev "1.1.2")
		(comment 9 "footprints 621-625 of 975")
	)
	(layers
		(0 "F.Cu" mixed)
		(4 "In1.Cu" power)
		(6 "In2.Cu" power)
		(8 "In3.Cu" mixed)
		(10 "In4.Cu" power)
		(12 "In5.Cu" mixed)
		(14 "In6.Cu" power)
		(16 "In7.Cu" mixed)
		(18 "In8.Cu" power)
		(2 "B.Cu" mixed)
		(9 "F.Adhes" user "F.Adhesive")
		(11 "B.Adhes" user "B.Adhesive")
		(13 "F.Paste" user)
		(15 "B.Paste" user)
		(5 "F.SilkS" user "F.Silkscreen")
		(7 "B.SilkS" user "B.Silkscreen")
		(1 "F.Mask" user)
		(3 "B.Mask" user)
		(17 "Dwgs.User" user "User.Drawings")
		(19 "Cmts.User" user "User.Comments")
		(21 "Eco1.User" user "User.Eco1")
		(23 "Eco2.User" user "User.Eco2")
		(25 "Edge.Cuts" user)
		(27 "Margin" user)
		(31 "F.CrtYd" user "F.Courtyard")
		(29 "B.CrtYd" user "B.Courtyard")
		(35 "F.Fab" user)
		(33 "B.Fab" user)
	)
	(footprint "antmicro-footprints:R_0402_1005Metric"
		(layer "B.Cu")
		(at 249.001 129.7 180)
		(descr "Resistor SMD 0402")
		(tags "resistor SMD 0402")
		(property "Reference" "R92"
			(at -1.099 -1.275 0)
			(layer "B.SilkS")
			(effects
				(font
					(size 0.7 0.7)
					(thickness 0.15)
				)
				(justify left bottom mirror)
			)
		)
		(property "Value" "R_10k_0402"
			(at 0 -1.4 0)
			(layer "B.Fab")
			(effects
				(font
					(size 0.7 0.7)
					(thickness 0.15)
				)
				(justify left bottom mirror)
			)
		)
		(property "Description" "SMD Chip Resistor, 10 kohm, ± 1%, 62.5 mW, 0402 [1005 Metric], Thick Film, General Purpose"
			(at 0 0 180)
			(layer "F.Fab")
			(hide yes)
			(effects
				(font
					(size 1.27 1.27)
					(thickness 0.15)
				)
			)
		)
		(property "Author" "Antmicro"
			(at 498.002 259.4 0)
			(layer "B.Fab")
			(hide yes)
			(effects
				(font
					(size 1 1)
					(thickness 0.15)
				)
				(justify mirror)
			)
		)
		(property "License" "Apache-2.0"
			(at 498.002 259.4 0)
			(layer "B.Fab")
			(hide yes)
			(effects
				(font
					(size 1 1)
					(thickness 0.15)
				)
				(justify mirror)
			)
		)
		(property "MPN" "CR0402-FX-1002GLF"
			(at 498.002 259.4 0)
			(layer "B.Fab")
			(hide yes)
			(effects
				(font
					(size 1 1)
					(thickness 0.15)
				)
				(justify mirror)
			)
		)
		(property "Manufacturer" "Bourns"
			(at 498.002 259.4 0)
			(layer "B.Fab")
			(hide yes)
			(effects
				(font
					(size 1 1)
					(thickness 0.15)
				)
				(justify mirror)
			)
		)
		(property "Tolerance" "1%"
			(at 498.002 259.4 0)
			(layer "B.Fab")
			(hide yes)
			(effects
				(font
					(size 1 1)
					(thickness 0.15)
				)
				(justify mirror)
			)
		)
		(property "Val" "10k"
			(at 498.002 259.4 0)
			(layer "B.Fab")
			(hide yes)
			(effects
				(font
					(size 1 1)
					(thickness 0.15)
				)
				(justify mirror)
			)
		)
		(sheetname "SPI Flash + SD Card")
		(sheetfile "spi-flash.kicad_sch")
		(attr smd)
		(fp_rect
			(start -0.925 0.47)
			(end 0.925 -0.47)
			(stroke
				(width 0.05)
				(type default)
			)
			(fill no)
			(layer "B.CrtYd")
		)
		(fp_rect
			(start -0.5 0.25)
			(end 0.5 -0.25)
			(stroke
				(width 0.15)
				(type solid)
			)
			(fill no)
			(layer "B.Fab")
		)
		(pad "1" smd roundrect
			(at -0.48 0 180)
			(size 0.59 0.64)
			(layers "B.Cu" "B.Mask" "B.Paste")
			(roundrect_rratio 0.25)
			(net 416 "/FPGA Bank 33 & 34/SD_CARD.~{CD}")
			(pintype "passive")
		)
		(pad "2" smd roundrect
			(at 0.48 0 180)
			(size 0.59 0.64)
			(layers "B.Cu" "B.Mask" "B.Paste")
			(roundrect_rratio 0.25)
			(net 24 "+3V3")
			(pintype "passive")
		)
	)
	(footprint "antmicro-footprints:USON-10_2.5x1mm_P0.5mm"
		(layer "B.Cu")
		(at 259.195 75.41 -90)
		(descr "USON-10 2.5x1mm_ Pitch 0.5mm")
		(tags "USON-10 2.5x1mm Pitch 0.5mm")
		(property "Reference" "U46"
			(at 1.69 -1.13 180)
			(layer "B.SilkS")
			(effects
				(font
					(size 0.7 0.7)
					(thickness 0.15)
				)
				(justify left bottom mirror)
			)
		)
		(property "Value" "TPD4E05U06QDQARQ1"
			(at 0.018 -2.499 90)
			(layer "B.Fab")
			(effects
				(font
					(size 0.7 0.7)
					(thickness 0.15)
				)
				(justify left bottom mirror)
			)
		)
		(property "Description" "ESD protection"
			(at 0 0 270)
			(layer "F.Fab")
			(hide yes)
			(effects
				(font
					(size 1.27 1.27)
					(thickness 0.15)
				)
			)
		)
		(property "Author" "Antmicro"
			(at 183.785 334.605 0)
			(layer "B.Fab")
			(hide yes)
			(effects
				(font
					(size 1 1)
					(thickness 0.15)
				)
				(justify mirror)
			)
		)
		(property "License" "Apache-2.0"
			(at 183.785 334.605 0)
			(layer "B.Fab")
			(hide yes)
			(effects
				(font
					(size 1 1)
					(thickness 0.15)
				)
				(justify mirror)
			)
		)
		(property "MPN" "TPD4E05U06QDQARQ1"
			(at 183.785 334.605 0)
			(layer "B.Fab")
			(hide yes)
			(effects
				(font
					(size 1 1)
					(thickness 0.15)
				)
				(justify mirror)
			)
		)
		(property "Manufacturer" "Texas Instruments"
			(at 183.785 334.605 0)
			(layer "B.Fab")
			(hide yes)
			(effects
				(font
					(size 1 1)
					(thickness 0.15)
				)
				(justify mirror)
			)
		)
		(sheetname "User GPIO + LED + button + DIP switch")
		(sheetfile "user-gpio.kicad_sch")
		(attr smd)
		(fp_line
			(start 0.498 1.401)
			(end -0.5 1.401)
			(stroke
				(width 0.15)
				(type solid)
			)
			(layer "B.SilkS")
		)
		(fp_line
			(start 0.498 -1.398)
			(end -0.5 -1.398)
			(stroke
				(width 0.15)
				(type solid)
			)
			(layer "B.SilkS")
		)
		(fp_circle
			(center -0.68 1.27)
			(end -0.63 1.27)
			(stroke
				(width 0.15)
				(type solid)
			)
			(fill yes)
			(layer "B.SilkS")
		)
		(fp_rect
			(start -0.8 1.5)
			(end 0.8 -1.499)
			(stroke
				(width 0.05)
				(type solid)
			)
			(fill no)
			(layer "B.CrtYd")
		)
		(fp_line
			(start -0.25 1.25)
			(end -0.5 1)
			(stroke
				(width 0.15)
				(type solid)
			)
			(layer "B.Fab")
		)
		(fp_line
			(start 0.498 1.25)
			(end -0.25 1.25)
			(stroke
				(width 0.15)
				(type solid)
			)
			(layer "B.Fab")
		)
		(fp_line
			(start 0.498 1.25)
			(end 0.498 -1.249)
			(stroke
				(width 0.15)
				(type solid)
			)
			(layer "B.Fab")
		)
		(fp_line
			(start -0.5 1)
			(end -0.5 -1.249)
			(stroke
				(width 0.15)
				(type solid)
			)
			(layer "B.Fab")
		)
		(fp_line
			(start -0.5 -1.249)
			(end 0.498 -1.249)
			(stroke
				(width 0.15)
				(type solid)
			)
			(layer "B.Fab")
		)
		(pad "1" smd roundrect
			(at -0.387 1)
			(size 0.25 0.55)
			(layers "B.Cu" "B.Mask" "B.Paste")
			(roundrect_rratio 0.25)
			(net 1324 "/USER_IO.DIP_SW4")
			(pintype "passive")
		)
		(pad "2" smd roundrect
			(at -0.387 0.5)
			(size 0.25 0.55)
			(layers "B.Cu" "B.Mask" "B.Paste")
			(roundrect_rratio 0.25)
			(net 1322 "/USER_IO.DIP_SW5")
			(pintype "passive")
		)
		(pad "3" smd roundrect
			(at -0.387 0)
			(size 0.4 0.55)
			(layers "B.Cu" "B.Mask" "B.Paste")
			(roundrect_rratio 0.25)
			(net 1 "GND")
			(pintype "power_in")
		)
		(pad "4" smd roundrect
			(at -0.387 -0.498)
			(size 0.25 0.55)
			(layers "B.Cu" "B.Mask" "B.Paste")
			(roundrect_rratio 0.25)
			(net 1320 "/USER_IO.DIP_SW6")
			(pintype "passive")
		)
		(pad "5" smd roundrect
			(at -0.387 -0.998)
			(size 0.25 0.55)
			(layers "B.Cu" "B.Mask" "B.Paste")
			(roundrect_rratio 0.25)
			(net 1318 "/USER_IO.DIP_SW7")
			(pintype "passive")
		)
		(pad "6" smd roundrect
			(at 0.385 -0.998)
			(size 0.25 0.55)
			(layers "B.Cu" "B.Mask" "B.Paste")
			(roundrect_rratio 0.25)
			(net 1318 "/USER_IO.DIP_SW7")
			(pintype "passive")
		)
		(pad "7" smd roundrect
			(at 0.385 -0.498)
			(size 0.25 0.55)
			(layers "B.Cu" "B.Mask" "B.Paste")
			(roundrect_rratio 0.25)
			(net 1320 "/USER_IO.DIP_SW6")
			(pintype "passive")
		)
		(pad "8" smd roundrect
			(at 0.385 0)
			(size 0.4 0.55)
			(layers "B.Cu" "B.Mask" "B.Paste")
			(roundrect_rratio 0.25)
			(net 1 "GND")
			(pintype "passive")
		)
		(pad "9" smd roundrect
			(at 0.385 0.5)
			(size 0.25 0.55)
			(layers "B.Cu" "B.Mask" "B.Paste")
			(roundrect_rratio 0.25)
			(net 1322 "/USER_IO.DIP_SW5")
			(pintype "passive")
		)
		(pad "10" smd roundrect
			(at 0.385 1)
			(size 0.25 0.55)
			(layers "B.Cu" "B.Mask" "B.Paste")
			(roundrect_rratio 0.25)
			(net 1324 "/USER_IO.DIP_SW4")
			(pintype "passive")
		)
	)
	(footprint "antmicro-footprints:USON-10_2.5x1mm_P0.5mm"
		(layer "B.Cu")
		(at 255.2 75.41 -90)
		(descr "USON-10 2.5x1mm_ Pitch 0.5mm")
		(tags "USON-10 2.5x1mm Pitch 0.5mm")
		(property "Reference" "U45"
			(at 1.69 -1.1 180)
			(layer "B.SilkS")
			(effects
				(font
					(size 0.7 0.7)
					(thickness 0.15)
				)
				(justify left bottom mirror)
			)
		)
		(property "Value" "TPD4E05U06QDQARQ1"
			(at 0.018 -2.499 90)
			(layer "B.Fab")
			(effects
				(font
					(size 0.7 0.7)
					(thickness 0.15)
				)
				(justify left bottom mirror)
			)
		)
		(property "Description" "ESD protection"
			(at 0 0 270)
			(layer "F.Fab")
			(hide yes)
			(effects
				(font
					(size 1.27 1.27)
					(thickness 0.15)
				)
			)
		)
		(property "Author" "Antmicro"
			(at 179.79 330.61 0)
			(layer "B.Fab")
			(hide yes)
			(effects
				(font
					(size 1 1)
					(thickness 0.15)
				)
				(justify mirror)
			)
		)
		(property "License" "Apache-2.0"
			(at 179.79 330.61 0)
			(layer "B.Fab")
			(hide yes)
			(effects
				(font
					(size 1 1)
					(thickness 0.15)
				)
				(justify mirror)
			)
		)
		(property "MPN" "TPD4E05U06QDQARQ1"
			(at 179.79 330.61 0)
			(layer "B.Fab")
			(hide yes)
			(effects
				(font
					(size 1 1)
					(thickness 0.15)
				)
				(justify mirror)
			)
		)
		(property "Manufacturer" "Texas Instruments"
			(at 179.79 330.61 0)
			(layer "B.Fab")
			(hide yes)
			(effects
				(font
					(size 1 1)
					(thickness 0.15)
				)
				(justify mirror)
			)
		)
		(sheetname "User GPIO + LED + button + DIP switch")
		(sheetfile "user-gpio.kicad_sch")
		(attr smd)
		(fp_line
			(start 0.498 1.401)
			(end -0.5 1.401)
			(stroke
				(width 0.15)
				(type solid)
			)
			(layer "B.SilkS")
		)
		(fp_line
			(start 0.498 -1.398)
			(end -0.5 -1.398)
			(stroke
				(width 0.15)
				(type solid)
			)
			(layer "B.SilkS")
		)
		(fp_circle
			(center -0.68 1.27)
			(end -0.63 1.27)
			(stroke
				(width 0.15)
				(type solid)
			)
			(fill yes)
			(layer "B.SilkS")
		)
		(fp_rect
			(start -0.8 1.5)
			(end 0.8 -1.499)
			(stroke
				(width 0.05)
				(type solid)
			)
			(fill no)
			(layer "B.CrtYd")
		)
		(fp_line
			(start -0.25 1.25)
			(end -0.5 1)
			(stroke
				(width 0.15)
				(type solid)
			)
			(layer "B.Fab")
		)
		(fp_line
			(start 0.498 1.25)
			(end -0.25 1.25)
			(stroke
				(width 0.15)
				(type solid)
			)
			(layer "B.Fab")
		)
		(fp_line
			(start 0.498 1.25)
			(end 0.498 -1.249)
			(stroke
				(width 0.15)
				(type solid)
			)
			(layer "B.Fab")
		)
		(fp_line
			(start -0.5 1)
			(end -0.5 -1.249)
			(stroke
				(width 0.15)
				(type solid)
			)
			(layer "B.Fab")
		)
		(fp_line
			(start -0.5 -1.249)
			(end 0.498 -1.249)
			(stroke
				(width 0.15)
				(type solid)
			)
			(layer "B.Fab")
		)
		(pad "1" smd roundrect
			(at -0.387 1)
			(size 0.25 0.55)
			(layers "B.Cu" "B.Mask" "B.Paste")
			(roundrect_rratio 0.25)
			(net 1311 "/USER_IO.DIP_SW0")
			(pintype "passive")
		)
		(pad "2" smd roundrect
			(at -0.387 0.5)
			(size 0.25 0.55)
			(layers "B.Cu" "B.Mask" "B.Paste")
			(roundrect_rratio 0.25)
			(net 1310 "/USER_IO.DIP_SW1")
			(pintype "passive")
		)
		(pad "3" smd roundrect
			(at -0.387 0)
			(size 0.4 0.55)
			(layers "B.Cu" "B.Mask" "B.Paste")
			(roundrect_rratio 0.25)
			(net 1 "GND")
			(pintype "power_in")
		)
		(pad "4" smd roundrect
			(at -0.387 -0.498)
			(size 0.25 0.55)
			(layers "B.Cu" "B.Mask" "B.Paste")
			(roundrect_rratio 0.25)
			(net 1309 "/USER_IO.DIP_SW2")
			(pintype "passive")
		)
		(pad "5" smd roundrect
			(at -0.387 -0.998)
			(size 0.25 0.55)
			(layers "B.Cu" "B.Mask" "B.Paste")
			(roundrect_rratio 0.25)
			(net 1308 "/USER_IO.DIP_SW3")
			(pintype "passive")
		)
		(pad "6" smd roundrect
			(at 0.385 -0.998)
			(size 0.25 0.55)
			(layers "B.Cu" "B.Mask" "B.Paste")
			(roundrect_rratio 0.25)
			(net 1308 "/USER_IO.DIP_SW3")
			(pintype "passive")
		)
		(pad "7" smd roundrect
			(at 0.385 -0.498)
			(size 0.25 0.55)
			(layers "B.Cu" "B.Mask" "B.Paste")
			(roundrect_rratio 0.25)
			(net 1309 "/USER_IO.DIP_SW2")
			(pintype "passive")
		)
		(pad "8" smd roundrect
			(at 0.385 0)
			(size 0.4 0.55)
			(layers "B.Cu" "B.Mask" "B.Paste")
			(roundrect_rratio 0.25)
			(net 1 "GND")
			(pintype "passive")
		)
		(pad "9" smd roundrect
			(at 0.385 0.5)
			(size 0.25 0.55)
			(layers "B.Cu" "B.Mask" "B.Paste")
			(roundrect_rratio 0.25)
			(net 1310 "/USER_IO.DIP_SW1")
			(pintype "passive")
		)
		(pad "10" smd roundrect
			(at 0.385 1)
			(size 0.25 0.55)
			(layers "B.Cu" "B.Mask" "B.Paste")
			(roundrect_rratio 0.25)
			(net 1311 "/USER_IO.DIP_SW0")
			(pintype "passive")
		)
	)
	(footprint "antmicro-footprints:NetTie-2_SMD_Pad0.127mm"
		(layer "B.Cu")
		(at 208.62 147.257001 90)
		(descr "Net tie, 2 pin, 0.127mm  SMD pads")
		(tags "net tie")
		(property "Reference" "NT32"
			(at -0.128 1.345 270)
			(layer "B.SilkS")
			(hide yes)
			(effects
				(font
					(size 0.7 0.7)
					(thickness 0.15)
				)
				(justify left bottom mirror)
			)
		)
		(property "Value" "Net-Tie_2"
			(at 0 -1.199 270)
			(layer "B.Fab")
			(effects
				(font
					(size 0.7 0.7)
					(thickness 0.15)
				)
				(justify left bottom mirror)
			)
		)
		(property "Description" "Net tie, 2 pins"
			(at 0 0 90)
			(layer "F.Fab")
			(hide yes)
			(effects
				(font
					(size 1.27 1.27)
					(thickness 0.15)
				)
			)
		)
		(property "Author" "Antmicro"
			(at 355.877001 -61.362999 0)
			(layer "B.Fab")
			(hide yes)
			(effects
				(font
					(size 1 1)
					(thickness 0.15)
				)
				(justify mirror)
			)
		)
		(property "License" "Apache-2.0"
			(at 355.877001 -61.362999 0)
			(layer "B.Fab")
			(hide yes)
			(effects
				(font
					(size 1 1)
					(thickness 0.15)
				)
				(justify mirror)
			)
		)
		(property "MPN" ""
			(at 355.877001 -61.362999 0)
			(layer "B.Fab")
			(hide yes)
			(effects
				(font
					(size 1 1)
					(thickness 0.15)
				)
				(justify mirror)
			)
		)
		(property "Manufacturer" ""
			(at 355.877001 -61.362999 0)
			(layer "B.Fab")
			(hide yes)
			(effects
				(font
					(size 1 1)
					(thickness 0.15)
				)
				(justify mirror)
			)
		)
		(sheetname "DC-DC Converters")
		(sheetfile "dc-dc.kicad_sch")
		(attr exclude_from_pos_files)
		(net_tie_pad_groups "1, 2")
		(fp_poly
			(pts
				(xy -0.0635 0.0635) (xy 0.0625 0.0635) (xy 0.0625 -0.0635) (xy -0.0635 -0.0635)
			)
			(stroke
				(width 0)
				(type solid)
			)
			(fill yes)
			(layer "B.Cu")
		)
		(pad "1" smd roundrect
			(at -0.127 0 270)
			(size 0.127 0.127)
			(layers "B.Cu")
			(roundrect_rratio 0.5)
			(chamfer_ratio 0)
			(chamfer top_left bottom_left)
			(net 1220 "/DC-DC Converters/SENSE_3V3_2_P")
			(pinfunction "1")
			(pintype "passive")
		)
		(pad "2" smd roundrect
			(at 0.126 0 90)
			(size 0.127 0.127)
			(layers "B.Cu")
			(roundrect_rratio 0.5)
			(chamfer_ratio 0)
			(chamfer top_left bottom_left)
			(net 24 "+3V3")
			(pinfunction "2")
			(pintype "passive")
		)
	)
	(footprint "antmicro-footprints:R_0402_1005Metric"
		(layer "B.Cu")
		(at 242.501 133.9)
		(descr "Resistor SMD 0402")
		(tags "resistor SMD 0402")
		(property "Reference" "R161"
			(at -0.751 0.4 180)
			(layer "B.SilkS")
			(effects
				(font
					(size 0.7 0.7)
					(thickness 0.15)
				)
				(justify left bottom mirror)
			)
		)
		(property "Value" "R_33R_0402"
			(at 0 -1.4 180)
			(layer "B.Fab")
			(effects
				(font
					(size 0.7 0.7)
					(thickness 0.15)
				)
				(justify left bottom mirror)
			)
		)
		(property "Description" "SMD Chip Resistor, 33 ohm, ± 1%, 62.5 mW, 0402 [1005 Metric], Thick Film, General Purpose"
			(at 0 0 0)
			(layer "F.Fab")
			(hide yes)
			(effects
				(font
					(size 1.27 1.27)
					(thickness 0.15)
				)
			)
		)
		(property "Author" "Antmicro"
			(at 0 0 0)
			(layer "B.Fab")
			(hide yes)
			(effects
				(font
					(size 1 1)
					(thickness 0.15)
				)
				(justify mirror)
			)
		)
		(property "License" "Apache-2.0"
			(at 0 0 0)
			(layer "B.Fab")
			(hide yes)
			(effects
				(font
					(size 1 1)
					(thickness 0.15)
				)
				(justify mirror)
			)
		)
		(property "MPN" "CR0402-FX-33R0GLF"
			(at 0 0 0)
			(layer "B.Fab")
			(hide yes)
			(effects
				(font
					(size 1 1)
					(thickness 0.15)
				)
				(justify mirror)
			)
		)
		(property "Manufacturer" "Bourns"
			(at 0 0 0)
			(layer "B.Fab")
			(hide yes)
			(effects
				(font
					(size 1 1)
					(thickness 0.15)
				)
				(justify mirror)
			)
		)
		(property "Tolerance" "1%"
			(at 0 0 0)
			(layer "B.Fab")
			(hide yes)
			(effects
				(font
					(size 1 1)
					(thickness 0.15)
				)
				(justify mirror)
			)
		)
		(property "Val" "33R"
			(at 0 0 0)
			(layer "B.Fab")
			(hide yes)
			(effects
				(font
					(size 1 1)
					(thickness 0.15)
				)
				(justify mirror)
			)
		)
		(sheetname "USB PHY")
		(sheetfile "usb-phy.kicad_sch")
		(attr smd)
		(fp_rect
			(start -0.925 0.47)
			(end 0.925 -0.47)
			(stroke
				(width 0.05)
				(type default)
			)
			(fill no)
			(layer "B.CrtYd")
		)
		(fp_rect
			(start -0.5 0.25)
			(end 0.5 -0.25)
			(stroke
				(width 0.15)
				(type solid)
			)
			(fill no)
			(layer "B.Fab")
		)
		(pad "1" smd roundrect
			(at -0.48 0)
			(size 0.59 0.64)
			(layers "B.Cu" "B.Mask" "B.Paste")
			(roundrect_rratio 0.25)
			(net 921 "/USB PHY/FTDI_UART0_TX")
			(pintype "passive")
		)
		(pad "2" smd roundrect
			(at 0.48 0)
			(size 0.59 0.64)
			(layers "B.Cu" "B.Mask" "B.Paste")
			(roundrect_rratio 0.25)
			(net 46 "/FPGA Bank 12 & 13/UART0.RX")
			(pintype "passive")
		)
	)
)
